(kicad_pcb
	(version 20260206)
	(generator "pcbnew")
	(generator_version "10.0")
	(general
		(thickness 1.6)
		(legacy_teardrops no)
	)
	(paper "A4")
	(title_block
		(title "03242023_DA0F0TMBIJ0_F0T_Motherboard_J_brd_V01_OCP.brd")
		(comment 1 "Grand Teton / footprints 389-395 of 6105")
	)
	(layers
		(0 "F.Cu" signal "TOP")
		(4 "In1.Cu" signal "GND")
		(6 "In2.Cu" signal "IN1")
		(8 "In3.Cu" signal "GND1")
		(10 "In4.Cu" signal "IN2")
		(12 "In5.Cu" signal "GND2")
		(14 "In6.Cu" signal "IN3")
		(16 "In7.Cu" signal "GND3")
		(18 "In8.Cu" signal "VCC")
		(20 "In9.Cu" signal "VCC1")
		(22 "In10.Cu" signal "GND4")
		(24 "In11.Cu" signal "IN4")
		(26 "In12.Cu" signal "GND5")
		(28 "In13.Cu" signal "IN5")
		(30 "In14.Cu" signal "GND6")
		(32 "In15.Cu" signal "IN6")
		(34 "In16.Cu" signal "GND7")
		(2 "B.Cu" signal "BOTTOM")
		(9 "F.Adhes" user "F.Adhesive")
		(11 "B.Adhes" user "B.Adhesive")
		(13 "F.Paste" user "Package Geometry/Pastemask Top")
		(15 "B.Paste" user "Package Geometry/Pastemask Bottom")
		(5 "F.SilkS" user "Ref Des/Silkscreen Top")
		(7 "B.SilkS" user "Ref Des/Silkscreen Bottom")
		(1 "F.Mask" user "Board Geometry/Soldermask Top")
		(3 "B.Mask" user "Board Geometry/Soldermask Bottom")
		(17 "Dwgs.User" user "User.Drawings")
		(19 "Cmts.User" user "User.Comments")
		(21 "Eco1.User" user "User.Eco1")
		(23 "Eco2.User" user "User.Eco2")
		(25 "Edge.Cuts" user "Board Geometry/Outline")
		(27 "Margin" user)
		(31 "F.CrtYd" user "Package Geometry/Place Bound Top")
		(29 "B.CrtYd" user "Package Geometry/Place Bound Bottom")
		(35 "F.Fab" user "Ref Des/Assembly Top")
		(33 "B.Fab" user "Ref Des/Assembly Bottom")
	)
	(footprint ""
		(layer "F.Cu")
		(at 36.789106 -178.52009)
		(property "Reference" "PC1287"
			(at 0 0 0)
			(layer "F.SilkS")
			(hide yes)
			(effects
				(font
					(size 1.27 1.27)
				)
			)
		)
		(property "Value" ""
			(at 0 0 0)
			(layer "F.Fab")
			(effects
				(font
					(size 1.27 1.27)
				)
			)
		)
		(duplicate_pad_numbers_are_jumpers no)
		(fp_line
			(start -1.524 -0.762)
			(end 1.524 -0.762)
			(stroke
				(width 0.1524)
				(type default)
			)
			(layer "F.SilkS")
		)
		(fp_line
			(start -1.524 0.762)
			(end -1.524 -0.762)
			(stroke
				(width 0.1524)
				(type default)
			)
			(layer "F.SilkS")
		)
		(fp_line
			(start 1.524 -0.762)
			(end 1.524 0.762)
			(stroke
				(width 0.1524)
				(type default)
			)
			(layer "F.SilkS")
		)
		(fp_line
			(start 1.524 0.762)
			(end -1.524 0.762)
			(stroke
				(width 0.1524)
				(type default)
			)
			(layer "F.SilkS")
		)
		(fp_line
			(start -1.1049 -0.724916)
			(end -1.1049 0.724916)
			(stroke
				(width 0.1)
				(type default)
			)
			(layer "F.Fab")
		)
		(fp_line
			(start -1.1049 0.724916)
			(end 1.1049 0.724916)
			(stroke
				(width 0.1)
				(type default)
			)
			(layer "F.Fab")
		)
		(fp_line
			(start 1.1049 -0.724916)
			(end -1.1049 -0.724916)
			(stroke
				(width 0.1)
				(type default)
			)
			(layer "F.Fab")
		)
		(fp_line
			(start 1.1049 0.724916)
			(end 1.1049 -0.724916)
			(stroke
				(width 0.1)
				(type default)
			)
			(layer "F.Fab")
		)
		(pad "1" smd rect
			(at -0.889 0 180)
			(size 1.016 1.27)
			(layers "F.Cu" "F.Mask" "F.Paste")
			(net "PVNN_MAIN_CPU1")
		)
		(pad "2" smd rect
			(at 0.889 0 180)
			(size 1.016 1.27)
			(layers "F.Cu" "F.Mask" "F.Paste")
			(net "GND")
		)
	)
	(footprint ""
		(layer "F.Cu")
		(at 365.46663 -245.634002 -90)
		(property "Reference" "C1001"
			(at 0 0 270)
			(layer "F.SilkS")
			(hide yes)
			(effects
				(font
					(size 1.27 1.27)
				)
			)
		)
		(property "Value" ""
			(at 0 0 270)
			(layer "F.Fab")
			(effects
				(font
					(size 1.27 1.27)
				)
			)
		)
		(duplicate_pad_numbers_are_jumpers no)
		(fp_line
			(start -0.7874 0.4064)
			(end -0.7874 -0.4064)
			(stroke
				(width 0.1524)
				(type default)
			)
			(layer "F.SilkS")
		)
		(fp_line
			(start 0.7874 0.4064)
			(end -0.7874 0.4064)
			(stroke
				(width 0.1524)
				(type default)
			)
			(layer "F.SilkS")
		)
		(fp_line
			(start -0.7874 -0.4064)
			(end 0.7874 -0.4064)
			(stroke
				(width 0.1524)
				(type default)
			)
			(layer "F.SilkS")
		)
		(fp_line
			(start 0.7874 -0.4064)
			(end 0.7874 0.4064)
			(stroke
				(width 0.1524)
				(type default)
			)
			(layer "F.SilkS")
		)
		(fp_line
			(start -0.67945 0.3048)
			(end -0.67945 -0.305054)
			(stroke
				(width 0.1)
				(type default)
			)
			(layer "F.Fab")
		)
		(fp_line
			(start -0.12065 0.3048)
			(end -0.67945 0.3048)
			(stroke
				(width 0.1)
				(type default)
			)
			(layer "F.Fab")
		)
		(fp_line
			(start 0.120396 0.3048)
			(end 0.120396 0.2794)
			(stroke
				(width 0.1)
				(type default)
			)
			(layer "F.Fab")
		)
		(fp_line
			(start 0.67945 0.3048)
			(end 0.120396 0.3048)
			(stroke
				(width 0.1)
				(type default)
			)
			(layer "F.Fab")
		)
		(fp_line
			(start -0.12065 0.2794)
			(end -0.12065 0.3048)
			(stroke
				(width 0.1)
				(type default)
			)
			(layer "F.Fab")
		)
		(fp_line
			(start 0.120396 0.2794)
			(end -0.12065 0.2794)
			(stroke
				(width 0.1)
				(type default)
			)
			(layer "F.Fab")
		)
		(fp_line
			(start -0.12065 -0.2794)
			(end 0.12065 -0.2794)
			(stroke
				(width 0.1)
				(type default)
			)
			(layer "F.Fab")
		)
		(fp_line
			(start 0.12065 -0.2794)
			(end 0.12065 -0.3048)
			(stroke
				(width 0.1)
				(type default)
			)
			(layer "F.Fab")
		)
		(fp_line
			(start 0.12065 -0.3048)
			(end 0.67945 -0.3048)
			(stroke
				(width 0.1)
				(type default)
			)
			(layer "F.Fab")
		)
		(fp_line
			(start 0.67945 -0.3048)
			(end 0.67945 0.3048)
			(stroke
				(width 0.1)
				(type default)
			)
			(layer "F.Fab")
		)
		(fp_line
			(start -0.67945 -0.305054)
			(end -0.12065 -0.305054)
			(stroke
				(width 0.1)
				(type default)
			)
			(layer "F.Fab")
		)
		(fp_line
			(start -0.12065 -0.305054)
			(end -0.12065 -0.2794)
			(stroke
				(width 0.1)
				(type default)
			)
			(layer "F.Fab")
		)
		(pad "1" smd circle
			(at -0.40005 0 270)
			(size 0 0)
			(layers "F.Cu" "F.Mask" "F.Paste")
			(net "PVCCIN_CPU0")
		)
		(pad "2" smd circle
			(at 0.40005 0 270)
			(size 0 0)
			(layers "F.Cu" "F.Mask" "F.Paste")
			(net "GND")
		)
	)
	(footprint ""
		(layer "F.Cu")
		(at 164.64788 -116.296948)
		(property "Reference" "R1551"
			(at 0 0 0)
			(layer "F.SilkS")
			(hide yes)
			(effects
				(font
					(size 1.27 1.27)
				)
			)
		)
		(property "Value" ""
			(at 0 0 0)
			(layer "F.Fab")
			(effects
				(font
					(size 1.27 1.27)
				)
			)
		)
		(duplicate_pad_numbers_are_jumpers no)
		(fp_line
			(start -0.7874 -0.4064)
			(end 0.7874 -0.4064)
			(stroke
				(width 0.1524)
				(type default)
			)
			(layer "F.SilkS")
		)
		(fp_line
			(start -0.7874 0.4064)
			(end -0.7874 -0.4064)
			(stroke
				(width 0.1524)
				(type default)
			)
			(layer "F.SilkS")
		)
		(fp_line
			(start 0.7874 -0.4064)
			(end 0.7874 0.4064)
			(stroke
				(width 0.1524)
				(type default)
			)
			(layer "F.SilkS")
		)
		(fp_line
			(start 0.7874 0.4064)
			(end -0.7874 0.4064)
			(stroke
				(width 0.1524)
				(type default)
			)
			(layer "F.SilkS")
		)
		(fp_line
			(start -0.67945 -0.305054)
			(end -0.12065 -0.305054)
			(stroke
				(width 0.1)
				(type default)
			)
			(layer "F.Fab")
		)
		(fp_line
			(start -0.67945 0.3048)
			(end -0.67945 -0.305054)
			(stroke
				(width 0.1)
				(type default)
			)
			(layer "F.Fab")
		)
		(fp_line
			(start -0.12065 -0.305054)
			(end -0.12065 -0.2794)
			(stroke
				(width 0.1)
				(type default)
			)
			(layer "F.Fab")
		)
		(fp_line
			(start -0.12065 -0.2794)
			(end 0.12065 -0.2794)
			(stroke
				(width 0.1)
				(type default)
			)
			(layer "F.Fab")
		)
		(fp_line
			(start -0.12065 0.2794)
			(end -0.12065 0.3048)
			(stroke
				(width 0.1)
				(type default)
			)
			(layer "F.Fab")
		)
		(fp_line
			(start -0.12065 0.3048)
			(end -0.67945 0.3048)
			(stroke
				(width 0.1)
				(type default)
			)
			(layer "F.Fab")
		)
		(fp_line
			(start 0.120396 0.2794)
			(end -0.12065 0.2794)
			(stroke
				(width 0.1)
				(type default)
			)
			(layer "F.Fab")
		)
		(fp_line
			(start 0.120396 0.3048)
			(end 0.120396 0.2794)
			(stroke
				(width 0.1)
				(type default)
			)
			(layer "F.Fab")
		)
		(fp_line
			(start 0.12065 -0.3048)
			(end 0.67945 -0.3048)
			(stroke
				(width 0.1)
				(type default)
			)
			(layer "F.Fab")
		)
		(fp_line
			(start 0.12065 -0.2794)
			(end 0.12065 -0.3048)
			(stroke
				(width 0.1)
				(type default)
			)
			(layer "F.Fab")
		)
		(fp_line
			(start 0.67945 -0.3048)
			(end 0.67945 0.3048)
			(stroke
				(width 0.1)
				(type default)
			)
			(layer "F.Fab")
		)
		(fp_line
			(start 0.67945 0.3048)
			(end 0.120396 0.3048)
			(stroke
				(width 0.1)
				(type default)
			)
			(layer "F.Fab")
		)
		(pad "1" smd circle
			(at -0.40005 0)
			(size 0 0)
			(layers "F.Cu" "F.Mask" "F.Paste")
			(net "P3V3_AUX")
		)
		(pad "2" smd circle
			(at 0.40005 0)
			(size 0 0)
			(layers "F.Cu" "F.Mask" "F.Paste")
			(net "SMB_1_PLD_3V3AUX_SDA_R1")
		)
	)
	(footprint ""
		(layer "F.Cu")
		(at 247.627394 -88.343486 -90)
		(property "Reference" "Y2"
			(at -0.708406 -3.345688 0)
			(unlocked yes)
			(layer "F.SilkS")
			(effects
				(font
					(size 0.7874 0.5842)
					(thickness 0.1524)
				)
				(justify left)
			)
		)
		(property "Value" ""
			(at 0 0 270)
			(layer "F.Fab")
			(effects
				(font
					(size 1.27 1.27)
				)
			)
		)
		(duplicate_pad_numbers_are_jumpers no)
		(fp_line
			(start -1.538732 1.937004)
			(end -1.538732 -1.937004)
			(stroke
				(width 0.1524)
				(type default)
			)
			(layer "F.SilkS")
		)
		(fp_line
			(start 1.538732 1.937004)
			(end -1.538732 1.937004)
			(stroke
				(width 0.1524)
				(type default)
			)
			(layer "F.SilkS")
		)
		(fp_line
			(start -1.538732 -1.937004)
			(end 1.538732 -1.937004)
			(stroke
				(width 0.1524)
				(type default)
			)
			(layer "F.SilkS")
		)
		(fp_line
			(start 1.538732 -1.937004)
			(end 1.538732 1.937004)
			(stroke
				(width 0.1524)
				(type default)
			)
			(layer "F.SilkS")
		)
		(fp_poly
			(pts
				(xy -1.168908 -3.171952) (xy -0.302514 -3.171952) (xy -0.735838 -2.305558)
			)
			(stroke
				(width 0)
				(type default)
			)
			(fill yes)
			(layer "F.SilkS")
		)
		(fp_line
			(start -1.299972 1.649984)
			(end -1.299972 -1.649984)
			(stroke
				(width 0.1)
				(type default)
			)
			(layer "F.Fab")
		)
		(fp_line
			(start 1.299972 1.649984)
			(end -1.299972 1.649984)
			(stroke
				(width 0.1)
				(type default)
			)
			(layer "F.Fab")
		)
		(fp_line
			(start -1.299972 -1.649984)
			(end 1.299972 -1.649984)
			(stroke
				(width 0.1)
				(type default)
			)
			(layer "F.Fab")
		)
		(fp_line
			(start 1.299972 -1.649984)
			(end 1.299972 1.649984)
			(stroke
				(width 0.1)
				(type default)
			)
			(layer "F.Fab")
		)
		(fp_poly
			(pts
				(xy -2.5908 -0.626872) (xy -2.5908 -1.493266) (xy -1.724406 -1.059942)
			)
			(stroke
				(width 0)
				(type default)
			)
			(fill yes)
			(layer "F.Fab")
		)
		(pad "1" smd rect
			(at -0.8001 -1.059942 270)
			(size 1.2192 1.4986)
			(layers "F.Cu" "F.Mask" "F.Paste")
			(net "XTAL_CLK_GEN1_25M_X1_R")
		)
		(pad "2" smd rect
			(at -0.8001 1.059942 270)
			(size 1.2192 1.4986)
			(layers "F.Cu" "F.Mask" "F.Paste")
			(net "GND")
		)
		(pad "3" smd rect
			(at 0.8001 1.059942 270)
			(size 1.2192 1.4986)
			(layers "F.Cu" "F.Mask" "F.Paste")
			(net "XTAL_CLK_GEN1_25M_X2")
		)
		(pad "4" smd rect
			(at 0.8001 -1.059942 270)
			(size 1.2192 1.4986)
			(layers "F.Cu" "F.Mask" "F.Paste")
			(net "GND")
		)
	)
	(footprint ""
		(layer "F.Cu")
		(at 33.065974 -163.475162)
		(property "Reference" "PR705"
			(at 0 0 0)
			(layer "F.SilkS")
			(hide yes)
			(effects
				(font
					(size 1.27 1.27)
				)
			)
		)
		(property "Value" ""
			(at 0 0 0)
			(layer "F.Fab")
			(effects
				(font
					(size 1.27 1.27)
				)
			)
		)
		(duplicate_pad_numbers_are_jumpers no)
		(fp_line
			(start -0.7874 -0.4064)
			(end 0.7874 -0.4064)
			(stroke
				(width 0.1524)
				(type default)
			)
			(layer "F.SilkS")
		)
		(fp_line
			(start -0.7874 0.4064)
			(end -0.7874 -0.4064)
			(stroke
				(width 0.1524)
				(type default)
			)
			(layer "F.SilkS")
		)
		(fp_line
			(start 0.7874 -0.4064)
			(end 0.7874 0.4064)
			(stroke
				(width 0.1524)
				(type default)
			)
			(layer "F.SilkS")
		)
		(fp_line
			(start 0.7874 0.4064)
			(end -0.7874 0.4064)
			(stroke
				(width 0.1524)
				(type default)
			)
			(layer "F.SilkS")
		)
		(fp_line
			(start -0.67945 -0.305054)
			(end -0.12065 -0.305054)
			(stroke
				(width 0.1)
				(type default)
			)
			(layer "F.Fab")
		)
		(fp_line
			(start -0.67945 0.3048)
			(end -0.67945 -0.305054)
			(stroke
				(width 0.1)
				(type default)
			)
			(layer "F.Fab")
		)
		(fp_line
			(start -0.12065 -0.305054)
			(end -0.12065 -0.2794)
			(stroke
				(width 0.1)
				(type default)
			)
			(layer "F.Fab")
		)
		(fp_line
			(start -0.12065 -0.2794)
			(end 0.12065 -0.2794)
			(stroke
				(width 0.1)
				(type default)
			)
			(layer "F.Fab")
		)
		(fp_line
			(start -0.12065 0.2794)
			(end -0.12065 0.3048)
			(stroke
				(width 0.1)
				(type default)
			)
			(layer "F.Fab")
		)
		(fp_line
			(start -0.12065 0.3048)
			(end -0.67945 0.3048)
			(stroke
				(width 0.1)
				(type default)
			)
			(layer "F.Fab")
		)
		(fp_line
			(start 0.120396 0.2794)
			(end -0.12065 0.2794)
			(stroke
				(width 0.1)
				(type default)
			)
			(layer "F.Fab")
		)
		(fp_line
			(start 0.120396 0.3048)
			(end 0.120396 0.2794)
			(stroke
				(width 0.1)
				(type default)
			)
			(layer "F.Fab")
		)
		(fp_line
			(start 0.12065 -0.3048)
			(end 0.67945 -0.3048)
			(stroke
				(width 0.1)
				(type default)
			)
			(layer "F.Fab")
		)
		(fp_line
			(start 0.12065 -0.2794)
			(end 0.12065 -0.3048)
			(stroke
				(width 0.1)
				(type default)
			)
			(layer "F.Fab")
		)
		(fp_line
			(start 0.67945 -0.3048)
			(end 0.67945 0.3048)
			(stroke
				(width 0.1)
				(type default)
			)
			(layer "F.Fab")
		)
		(fp_line
			(start 0.67945 0.3048)
			(end 0.120396 0.3048)
			(stroke
				(width 0.1)
				(type default)
			)
			(layer "F.Fab")
		)
		(pad "1" smd circle
			(at -0.40005 0)
			(size 0 0)
			(layers "F.Cu" "F.Mask" "F.Paste")
			(net "PVCCD_HV_CPU1_ATSEN")
		)
		(pad "2" smd circle
			(at 0.40005 0)
			(size 0 0)
			(layers "F.Cu" "F.Mask" "F.Paste")
			(net "GND")
		)
	)
	(footprint ""
		(layer "F.Cu")
		(at 173.216062 -31.34868 180)
		(property "Reference" "R4709"
			(at 0 0 180)
			(layer "F.SilkS")
			(hide yes)
			(effects
				(font
					(size 1.27 1.27)
				)
			)
		)
		(property "Value" ""
			(at 0 0 180)
			(layer "F.Fab")
			(effects
				(font
					(size 1.27 1.27)
				)
			)
		)
		(duplicate_pad_numbers_are_jumpers no)
		(fp_line
			(start 0.7874 0.4064)
			(end -0.7874 0.4064)
			(stroke
				(width 0.1524)
				(type default)
			)
			(layer "F.SilkS")
		)
		(fp_line
			(start 0.7874 -0.4064)
			(end 0.7874 0.4064)
			(stroke
				(width 0.1524)
				(type default)
			)
			(layer "F.SilkS")
		)
		(fp_line
			(start -0.7874 0.4064)
			(end -0.7874 -0.4064)
			(stroke
				(width 0.1524)
				(type default)
			)
			(layer "F.SilkS")
		)
		(fp_line
			(start -0.7874 -0.4064)
			(end 0.7874 -0.4064)
			(stroke
				(width 0.1524)
				(type default)
			)
			(layer "F.SilkS")
		)
		(fp_line
			(start 0.67945 0.3048)
			(end 0.120396 0.3048)
			(stroke
				(width 0.1)
				(type default)
			)
			(layer "F.Fab")
		)
		(fp_line
			(start 0.67945 -0.3048)
			(end 0.67945 0.3048)
			(stroke
				(width 0.1)
				(type default)
			)
			(layer "F.Fab")
		)
		(fp_line
			(start 0.12065 -0.2794)
			(end 0.12065 -0.3048)
			(stroke
				(width 0.1)
				(type default)
			)
			(layer "F.Fab")
		)
		(fp_line
			(start 0.12065 -0.3048)
			(end 0.67945 -0.3048)
			(stroke
				(width 0.1)
				(type default)
			)
			(layer "F.Fab")
		)
		(fp_line
			(start 0.120396 0.3048)
			(end 0.120396 0.2794)
			(stroke
				(width 0.1)
				(type default)
			)
			(layer "F.Fab")
		)
		(fp_line
			(start 0.120396 0.2794)
			(end -0.12065 0.2794)
			(stroke
				(width 0.1)
				(type default)
			)
			(layer "F.Fab")
		)
		(fp_line
			(start -0.12065 0.3048)
			(end -0.67945 0.3048)
			(stroke
				(width 0.1)
				(type default)
			)
			(layer "F.Fab")
		)
		(fp_line
			(start -0.12065 0.2794)
			(end -0.12065 0.3048)
			(stroke
				(width 0.1)
				(type default)
			)
			(layer "F.Fab")
		)
		(fp_line
			(start -0.12065 -0.2794)
			(end 0.12065 -0.2794)
			(stroke
				(width 0.1)
				(type default)
			)
			(layer "F.Fab")
		)
		(fp_line
			(start -0.12065 -0.305054)
			(end -0.12065 -0.2794)
			(stroke
				(width 0.1)
				(type default)
			)
			(layer "F.Fab")
		)
		(fp_line
			(start -0.67945 0.3048)
			(end -0.67945 -0.305054)
			(stroke
				(width 0.1)
				(type default)
			)
			(layer "F.Fab")
		)
		(fp_line
			(start -0.67945 -0.305054)
			(end -0.12065 -0.305054)
			(stroke
				(width 0.1)
				(type default)
			)
			(layer "F.Fab")
		)
		(pad "1" smd circle
			(at -0.40005 0 180)
			(size 0 0)
			(layers "F.Cu" "F.Mask" "F.Paste")
			(net "P12V_SCM_FLTB_N")
		)
		(pad "2" smd circle
			(at 0.40005 0 180)
			(size 0 0)
			(layers "F.Cu" "F.Mask" "F.Paste")
			(net "P12V_SCM_FAULT_R_N")
		)
	)
	(footprint ""
		(layer "F.Cu")
		(at 192.052448 -403.144482)
		(property "Reference" "R2588"
			(at 0 0 0)
			(layer "F.SilkS")
			(hide yes)
			(effects
				(font
					(size 1.27 1.27)
				)
			)
		)
		(property "Value" ""
			(at 0 0 0)
			(layer "F.Fab")
			(effects
				(font
					(size 1.27 1.27)
				)
			)
		)
		(duplicate_pad_numbers_are_jumpers no)
		(fp_line
			(start -0.7874 -0.4064)
			(end 0.7874 -0.4064)
			(stroke
				(width 0.1524)
				(type default)
			)
			(layer "F.SilkS")
		)
		(fp_line
			(start -0.7874 0.4064)
			(end -0.7874 -0.4064)
			(stroke
				(width 0.1524)
				(type default)
			)
			(layer "F.SilkS")
		)
		(fp_line
			(start 0.7874 -0.4064)
			(end 0.7874 0.4064)
			(stroke
				(width 0.1524)
				(type default)
			)
			(layer "F.SilkS")
		)
		(fp_line
			(start 0.7874 0.4064)
			(end -0.7874 0.4064)
			(stroke
				(width 0.1524)
				(type default)
			)
			(layer "F.SilkS")
		)
		(fp_line
			(start -0.67945 -0.305054)
			(end -0.12065 -0.305054)
			(stroke
				(width 0.1)
				(type default)
			)
			(layer "F.Fab")
		)
		(fp_line
			(start -0.67945 0.3048)
			(end -0.67945 -0.305054)
			(stroke
				(width 0.1)
				(type default)
			)
			(layer "F.Fab")
		)
		(fp_line
			(start -0.12065 -0.305054)
			(end -0.12065 -0.2794)
			(stroke
				(width 0.1)
				(type default)
			)
			(layer "F.Fab")
		)
		(fp_line
			(start -0.12065 -0.2794)
			(end 0.12065 -0.2794)
			(stroke
				(width 0.1)
				(type default)
			)
			(layer "F.Fab")
		)
		(fp_line
			(start -0.12065 0.2794)
			(end -0.12065 0.3048)
			(stroke
				(width 0.1)
				(type default)
			)
			(layer "F.Fab")
		)
		(fp_line
			(start -0.12065 0.3048)
			(end -0.67945 0.3048)
			(stroke
				(width 0.1)
				(type default)
			)
			(layer "F.Fab")
		)
		(fp_line
			(start 0.120396 0.2794)
			(end -0.12065 0.2794)
			(stroke
				(width 0.1)
				(type default)
			)
			(layer "F.Fab")
		)
		(fp_line
			(start 0.120396 0.3048)
			(end 0.120396 0.2794)
			(stroke
				(width 0.1)
				(type default)
			)
			(layer "F.Fab")
		)
		(fp_line
			(start 0.12065 -0.3048)
			(end 0.67945 -0.3048)
			(stroke
				(width 0.1)
				(type default)
			)
			(layer "F.Fab")
		)
		(fp_line
			(start 0.12065 -0.2794)
			(end 0.12065 -0.3048)
			(stroke
				(width 0.1)
				(type default)
			)
			(layer "F.Fab")
		)
		(fp_line
			(start 0.67945 -0.3048)
			(end 0.67945 0.3048)
			(stroke
				(width 0.1)
				(type default)
			)
			(layer "F.Fab")
		)
		(fp_line
			(start 0.67945 0.3048)
			(end 0.120396 0.3048)
			(stroke
				(width 0.1)
				(type default)
			)
			(layer "F.Fab")
		)
		(pad "1" smd circle
			(at -0.40005 0)
			(size 0 0)
			(layers "F.Cu" "F.Mask" "F.Paste")
			(net "HSC_FAULT")
		)
		(pad "2" smd circle
			(at 0.40005 0)
			(size 0 0)
			(layers "F.Cu" "F.Mask" "F.Paste")
			(net "IRQ_HSC_FAULT_N")
		)
	)
)
